(kicad_pcb
	(version 20260206)
	(generator "pcbnew")
	(generator_version "10.0")
	(general
		(thickness 1.6)
		(legacy_teardrops no)
	)
	(paper "A4")
	(title_block
		(title "Wiwynn_Tioga_Pass_MB.brd")
		(comment 1 "Tioga Pass / footprints 8-14 of 4770")
	)
	(layers
		(0 "F.Cu" signal "TOP")
		(4 "In1.Cu" signal "L2GND")
		(6 "In2.Cu" signal "L3")
		(8 "In3.Cu" signal "L4GND")
		(10 "In4.Cu" signal "L5")
		(12 "In5.Cu" signal "L6GND")
		(14 "In6.Cu" signal "L7VCC")
		(16 "In7.Cu" signal "L8VCC")
		(18 "In8.Cu" signal "L9GND")
		(20 "In9.Cu" signal "L10")
		(22 "In10.Cu" signal "L11GND")
		(24 "In11.Cu" signal "L12")
		(26 "In12.Cu" signal "L13GND")
		(2 "B.Cu" signal "BOTTOM")
		(9 "F.Adhes" user "F.Adhesive")
		(11 "B.Adhes" user "B.Adhesive")
		(13 "F.Paste" user "Package Geometry/Pastemask Top")
		(15 "B.Paste" user "Package Geometry/Pastemask Bottom")
		(5 "F.SilkS" user "Ref Des/Silkscreen Top")
		(7 "B.SilkS" user "Ref Des/Silkscreen Bottom")
		(1 "F.Mask" user "Board Geometry/Soldermask Top")
		(3 "B.Mask" user "Board Geometry/Soldermask Bottom")
		(17 "Dwgs.User" user "User.Drawings")
		(19 "Cmts.User" user "User.Comments")
		(21 "Eco1.User" user "User.Eco1")
		(23 "Eco2.User" user "User.Eco2")
		(25 "Edge.Cuts" user "Board Geometry/Outline")
		(27 "Margin" user)
		(31 "F.CrtYd" user "Package Geometry/Place Bound Top")
		(29 "B.CrtYd" user "Package Geometry/Place Bound Bottom")
		(35 "F.Fab" user "Ref Des/Assembly Top")
		(33 "B.Fab" user "Ref Des/Assembly Bottom")
	)
	(footprint ""
		(layer "F.Cu")
		(at 382.898904 -76.019406 180)
		(property "Reference" "R2T40"
			(at 0 0 180)
			(layer "F.SilkS")
			(hide yes)
			(effects
				(font
					(size 1.27 1.27)
				)
			)
		)
		(property "Value" ""
			(at 0 0 180)
			(layer "F.Fab")
			(effects
				(font
					(size 1.27 1.27)
				)
			)
		)
		(duplicate_pad_numbers_are_jumpers no)
		(fp_poly
			(pts
				(xy -0.2794 -0.1016) (xy 0.2794 -0.1016) (xy 0.2794 0.9906) (xy -0.2794 0.9906)
			)
			(stroke
				(width 0)
				(type default)
			)
			(fill no)
			(layer "F.CrtYd")
		)
		(fp_line
			(start 0.2794 0.9906)
			(end 0.2794 -0.1016)
			(stroke
				(width 0.1)
				(type default)
			)
			(layer "F.Fab")
		)
		(fp_line
			(start 0.2794 -0.1016)
			(end -0.2794 -0.1016)
			(stroke
				(width 0.1)
				(type default)
			)
			(layer "F.Fab")
		)
		(fp_line
			(start -0.2794 0.9906)
			(end 0.2794 0.9906)
			(stroke
				(width 0.1)
				(type default)
			)
			(layer "F.Fab")
		)
		(fp_line
			(start -0.2794 -0.1016)
			(end -0.2794 0.9906)
			(stroke
				(width 0.1)
				(type default)
			)
			(layer "F.Fab")
		)
		(pad "1" smd rect
			(at 0 0 180)
			(size 0.508 0.508)
			(layers "F.Cu" "F.Mask" "F.Paste")
			(net "H_CPU0_ERR2_G_N")
		)
		(pad "2" smd rect
			(at 0 0.889 180)
			(size 0.508 0.508)
			(layers "F.Cu" "F.Mask" "F.Paste")
			(net "H_CPU_ERR2_G_R_N")
		)
		(zone
			(layer "F.Cu")
			(hatch none 0.5)
			(connect_pads
				(clearance 0)
			)
			(min_thickness 0.25)
			(keepout
				(tracks not_allowed)
				(vias allowed)
				(pads allowed)
				(copperpour not_allowed)
				(footprints allowed)
			)
			(placement
				(enabled no)
				(sheetname "")
			)
			(fill
				(thermal_gap 0.5)
				(thermal_bridge_width 0.5)
				(island_removal_mode 0)
			)
			(polygon
				(pts
					(xy 383.152904 -76.654406) (xy 382.644904 -76.654406) (xy 382.644904 -76.273406) (xy 383.152904 -76.273406)
				)
			)
		)
		(zone
			(layer "F.Cu")
			(hatch none 0.5)
			(connect_pads
				(clearance 0)
			)
			(min_thickness 0.25)
			(keepout
				(tracks allowed)
				(vias not_allowed)
				(pads allowed)
				(copperpour not_allowed)
				(footprints allowed)
			)
			(placement
				(enabled no)
				(sheetname "")
			)
			(fill
				(thermal_gap 0.5)
				(thermal_bridge_width 0.5)
				(island_removal_mode 0)
			)
			(polygon
				(pts
					(xy 383.152904 -76.273406) (xy 382.644904 -76.273406) (xy 382.644904 -76.654406) (xy 383.152904 -76.654406)
				)
			)
		)
	)
	(footprint ""
		(layer "F.Cu")
		(at 401.752816 -147.928584 90)
		(property "Reference" "EU8A2"
			(at 0.228346 -5.106416 0)
			(unlocked yes)
			(layer "F.SilkS")
			(effects
				(font
					(size 0.7874 0.5842)
					(thickness 0.1524)
				)
				(justify left)
			)
		)
		(property "Value" ""
			(at 0 0 90)
			(layer "F.Fab")
			(effects
				(font
					(size 1.27 1.27)
				)
			)
		)
		(duplicate_pad_numbers_are_jumpers no)
		(fp_circle
			(center -0.835152 -0.417322)
			(end -0.835152 -0.290576)
			(stroke
				(width 0.254)
				(type default)
			)
			(fill no)
			(layer "F.SilkS")
		)
		(fp_poly
			(pts
				(xy -0.064516 -1.0922) (xy -0.064516 -0.3302) (xy 0.697484 -1.0922)
			)
			(stroke
				(width 0)
				(type default)
			)
			(fill yes)
			(layer "F.SilkS")
		)
		(fp_rect
			(start 0.597408 2.295398)
			(end 2.273808 -0.295402)
			(stroke
				(width 0)
				(type default)
			)
			(fill yes)
			(layer "F.Paste")
		)
		(fp_rect
			(start -0.064516 2.500122)
			(end 2.935478 -0.500126)
			(stroke
				(width 0)
				(type default)
			)
			(fill no)
			(layer "F.CrtYd")
		)
		(fp_line
			(start 2.935478 -0.500126)
			(end 2.935478 2.500122)
			(stroke
				(width 0.1)
				(type default)
			)
			(layer "F.Fab")
		)
		(fp_line
			(start -0.064516 -0.500126)
			(end 2.935478 -0.500126)
			(stroke
				(width 0.1)
				(type default)
			)
			(layer "F.Fab")
		)
		(fp_line
			(start 2.935478 2.500122)
			(end -0.064516 2.500122)
			(stroke
				(width 0.1)
				(type default)
			)
			(layer "F.Fab")
		)
		(fp_line
			(start -0.064516 2.500122)
			(end -0.064516 -0.500126)
			(stroke
				(width 0.1)
				(type default)
			)
			(layer "F.Fab")
		)
		(fp_circle
			(center -0.835152 -0.417322)
			(end -0.835152 -0.290576)
			(stroke
				(width 0.254)
				(type default)
			)
			(fill no)
			(layer "F.Fab")
		)
		(pad "1" smd rect
			(at 0 0 90)
			(size 0.6858 0.3048)
			(layers "F.Cu" "F.Mask" "F.Paste")
			(net "P1V8_PCH_STBY")
		)
		(pad "2" smd rect
			(at 0 0.500126 90)
			(size 0.6858 0.3048)
			(layers "F.Cu" "F.Mask" "F.Paste")
			(net "P1V8_PCH_STBY")
		)
		(pad "3" smd rect
			(at 0 0.999998 90)
			(size 0.6858 0.3048)
			(layers "F.Cu" "F.Mask" "F.Paste")
			(net "P1V8_PCH_STBY")
		)
		(pad "4" smd rect
			(at 0 1.500124 90)
			(size 0.6858 0.3048)
			(layers "F.Cu" "F.Mask" "F.Paste")
			(net "VR_P1V8_PCH_STBY_FB")
		)
		(pad "5" smd rect
			(at 0 1.999996 90)
			(size 0.6858 0.3048)
			(layers "F.Cu" "F.Mask" "F.Paste")
			(net "PWRGD_P1V8_PCH_STBY_R")
		)
		(pad "6" smd rect
			(at 2.871216 1.999996 90)
			(size 0.6858 0.3048)
			(layers "F.Cu" "F.Mask" "F.Paste")
			(net "PWRGD_P3V3_STBY")
		)
		(pad "7" smd rect
			(at 2.871216 1.500124 90)
			(size 0.6858 0.3048)
			(layers "F.Cu" "F.Mask" "F.Paste")
			(net "P3V3_STBY")
		)
		(pad "8" smd rect
			(at 2.871216 0.999998 90)
			(size 0.6858 0.3048)
			(layers "F.Cu" "F.Mask" "F.Paste")
			(net "P3V3_STBY")
		)
		(pad "9" smd rect
			(at 2.871216 0.500126 90)
			(size 0.6858 0.3048)
			(layers "F.Cu" "F.Mask" "F.Paste")
			(net "P3V3_STBY")
		)
		(pad "10" smd rect
			(at 2.871216 0 90)
			(size 0.6858 0.3048)
			(layers "F.Cu" "F.Mask" "F.Paste")
			(net "P3V3_STBY")
		)
		(pad "11" smd rect
			(at 1.435608 0.999998 90)
			(size 1.6764 2.5908)
			(layers "F.Cu" "F.Mask" "F.Paste")
			(net "GND")
		)
	)
	(footprint ""
		(layer "F.Cu")
		(at 335.292446 -129.480564)
		(property "Reference" "R7B10"
			(at 0 0 0)
			(layer "F.SilkS")
			(hide yes)
			(effects
				(font
					(size 1.27 1.27)
				)
			)
		)
		(property "Value" ""
			(at 0 0 0)
			(layer "F.Fab")
			(effects
				(font
					(size 1.27 1.27)
				)
			)
		)
		(duplicate_pad_numbers_are_jumpers no)
		(fp_poly
			(pts
				(xy -0.4953 -0.2032) (xy 0.4953 -0.2032) (xy 0.4953 1.6002) (xy -0.4953 1.6002)
			)
			(stroke
				(width 0)
				(type default)
			)
			(fill no)
			(layer "F.CrtYd")
		)
		(fp_line
			(start -0.4953 -0.2032)
			(end 0.4953 -0.2032)
			(stroke
				(width 0.1)
				(type default)
			)
			(layer "F.Fab")
		)
		(fp_line
			(start -0.4953 1.6002)
			(end -0.4953 -0.2032)
			(stroke
				(width 0.1)
				(type default)
			)
			(layer "F.Fab")
		)
		(fp_line
			(start 0.4953 -0.2032)
			(end 0.4953 1.6002)
			(stroke
				(width 0.1)
				(type default)
			)
			(layer "F.Fab")
		)
		(fp_line
			(start 0.4953 1.6002)
			(end -0.4953 1.6002)
			(stroke
				(width 0.1)
				(type default)
			)
			(layer "F.Fab")
		)
		(pad "1" smd rect
			(at 0 0)
			(size 0.762 0.889)
			(layers "F.Cu" "F.Mask" "F.Paste")
			(net "PVPP_DEF")
		)
		(pad "2" smd rect
			(at 0 1.397)
			(size 0.762 0.889)
			(layers "F.Cu" "F.Mask" "F.Paste")
			(net "GND")
		)
		(zone
			(layer "F.Cu")
			(hatch none 0.5)
			(connect_pads
				(clearance 0)
			)
			(min_thickness 0.25)
			(keepout
				(tracks not_allowed)
				(vias allowed)
				(pads allowed)
				(copperpour not_allowed)
				(footprints allowed)
			)
			(placement
				(enabled no)
				(sheetname "")
			)
			(fill
				(thermal_gap 0.5)
				(thermal_bridge_width 0.5)
				(island_removal_mode 0)
			)
			(polygon
				(pts
					(xy 334.911446 -128.528064) (xy 335.673446 -128.528064) (xy 335.673446 -129.036064) (xy 334.911446 -129.036064)
				)
			)
		)
		(zone
			(layer "F.Cu")
			(hatch none 0.5)
			(connect_pads
				(clearance 0)
			)
			(min_thickness 0.25)
			(keepout
				(tracks allowed)
				(vias not_allowed)
				(pads allowed)
				(copperpour not_allowed)
				(footprints allowed)
			)
			(placement
				(enabled no)
				(sheetname "")
			)
			(fill
				(thermal_gap 0.5)
				(thermal_bridge_width 0.5)
				(island_removal_mode 0)
			)
			(polygon
				(pts
					(xy 335.673446 -128.528064) (xy 335.673446 -129.036064) (xy 334.911446 -129.036064) (xy 334.911446 -128.528064)
				)
			)
		)
	)
	(footprint ""
		(layer "F.Cu")
		(at 490.453934 -148.717 -90)
		(property "Reference" "U9A1"
			(at -1.09855 1.85928 0)
			(unlocked yes)
			(layer "F.SilkS")
			(effects
				(font
					(size 0.7874 0.5842)
					(thickness 0.1524)
				)
				(justify left)
			)
		)
		(property "Value" ""
			(at 0 0 270)
			(layer "F.Fab")
			(effects
				(font
					(size 1.27 1.27)
				)
			)
		)
		(duplicate_pad_numbers_are_jumpers no)
		(fp_circle
			(center -0.4699 -0.8382)
			(end -0.4699 -0.9652)
			(stroke
				(width 0.254)
				(type default)
			)
			(fill no)
			(layer "F.SilkS")
		)
		(fp_poly
			(pts
				(xy 0.21463 -0.450088) (xy 1.56337 -0.450088) (xy 1.56337 1.75006) (xy 0.21463 1.75006)
			)
			(stroke
				(width 0)
				(type default)
			)
			(fill no)
			(layer "F.CrtYd")
		)
		(fp_line
			(start 0.21463 1.75006)
			(end 0.21463 -0.450088)
			(stroke
				(width 0.1)
				(type default)
			)
			(layer "F.Fab")
		)
		(fp_line
			(start 1.56337 1.75006)
			(end 0.21463 1.75006)
			(stroke
				(width 0.1)
				(type default)
			)
			(layer "F.Fab")
		)
		(fp_line
			(start 0.21463 -0.450088)
			(end 1.56337 -0.450088)
			(stroke
				(width 0.1)
				(type default)
			)
			(layer "F.Fab")
		)
		(fp_line
			(start 1.56337 -0.450088)
			(end 1.56337 1.75006)
			(stroke
				(width 0.1)
				(type default)
			)
			(layer "F.Fab")
		)
		(fp_circle
			(center -0.4699 -0.8382)
			(end -0.4699 -0.9652)
			(stroke
				(width 0.254)
				(type default)
			)
			(fill no)
			(layer "F.Fab")
		)
		(pad "1" smd rect
			(at 0 0 270)
			(size 1.016 0.381)
			(layers "F.Cu" "F.Mask" "F.Paste")
			(net "Net_6476")
		)
		(pad "2" smd rect
			(at 0 0.649986 270)
			(size 1.016 0.381)
			(layers "F.Cu" "F.Mask" "F.Paste")
			(net "SPA_5V_SIN_SW_D")
		)
		(pad "3" smd rect
			(at 0 1.299972 270)
			(size 1.016 0.381)
			(layers "F.Cu" "F.Mask" "F.Paste")
			(net "GND")
		)
		(pad "4" smd rect
			(at 1.778 1.299972 270)
			(size 1.016 0.381)
			(layers "F.Cu" "F.Mask" "F.Paste")
			(net "SPA_SIN_SW_R")
		)
		(pad "5" smd rect
			(at 1.778 0 270)
			(size 1.016 0.381)
			(layers "F.Cu" "F.Mask" "F.Paste")
			(net "P3V3_STBY")
		)
	)
	(footprint ""
		(layer "F.Cu")
		(at 318.8716 -30.585918)
		(property "Reference" "R6F6"
			(at 0 0 0)
			(layer "F.SilkS")
			(hide yes)
			(effects
				(font
					(size 1.27 1.27)
				)
			)
		)
		(property "Value" ""
			(at 0 0 0)
			(layer "F.Fab")
			(effects
				(font
					(size 1.27 1.27)
				)
			)
		)
		(duplicate_pad_numbers_are_jumpers no)
		(fp_poly
			(pts
				(xy -0.2794 -0.1016) (xy 0.2794 -0.1016) (xy 0.2794 0.9906) (xy -0.2794 0.9906)
			)
			(stroke
				(width 0)
				(type default)
			)
			(fill no)
			(layer "F.CrtYd")
		)
		(fp_line
			(start -0.2794 -0.1016)
			(end -0.2794 0.9906)
			(stroke
				(width 0.1)
				(type default)
			)
			(layer "F.Fab")
		)
		(fp_line
			(start -0.2794 0.9906)
			(end 0.2794 0.9906)
			(stroke
				(width 0.1)
				(type default)
			)
			(layer "F.Fab")
		)
		(fp_line
			(start 0.2794 -0.1016)
			(end -0.2794 -0.1016)
			(stroke
				(width 0.1)
				(type default)
			)
			(layer "F.Fab")
		)
		(fp_line
			(start 0.2794 0.9906)
			(end 0.2794 -0.1016)
			(stroke
				(width 0.1)
				(type default)
			)
			(layer "F.Fab")
		)
		(pad "1" smd rect
			(at 0 0)
			(size 0.508 0.508)
			(layers "F.Cu" "F.Mask" "F.Paste")
			(net "CLK_322M_156M_CPU0_OSC_VRM_DN")
		)
		(pad "2" smd rect
			(at 0 0.889)
			(size 0.508 0.508)
			(layers "F.Cu" "F.Mask" "F.Paste")
			(net "CLK_156M_OSC_CPU0_HFI_DN")
		)
		(zone
			(layer "F.Cu")
			(hatch none 0.5)
			(connect_pads
				(clearance 0)
			)
			(min_thickness 0.25)
			(keepout
				(tracks allowed)
				(vias not_allowed)
				(pads allowed)
				(copperpour not_allowed)
				(footprints allowed)
			)
			(placement
				(enabled no)
				(sheetname "")
			)
			(fill
				(thermal_gap 0.5)
				(thermal_bridge_width 0.5)
				(island_removal_mode 0)
			)
			(polygon
				(pts
					(xy 318.6176 -30.331918) (xy 319.1256 -30.331918) (xy 319.1256 -29.950918) (xy 318.6176 -29.950918)
				)
			)
		)
		(zone
			(layer "F.Cu")
			(hatch none 0.5)
			(connect_pads
				(clearance 0)
			)
			(min_thickness 0.25)
			(keepout
				(tracks not_allowed)
				(vias allowed)
				(pads allowed)
				(copperpour not_allowed)
				(footprints allowed)
			)
			(placement
				(enabled no)
				(sheetname "")
			)
			(fill
				(thermal_gap 0.5)
				(thermal_bridge_width 0.5)
				(island_removal_mode 0)
			)
			(polygon
				(pts
					(xy 318.6176 -29.950918) (xy 319.1256 -29.950918) (xy 319.1256 -30.331918) (xy 318.6176 -30.331918)
				)
			)
		)
	)
	(footprint ""
		(layer "F.Cu")
		(at 320.04 -130.3528 90)
		(property "Reference" "C6B2"
			(at 0 0 90)
			(layer "F.SilkS")
			(hide yes)
			(effects
				(font
					(size 1.27 1.27)
				)
			)
		)
		(property "Value" ""
			(at 0 0 90)
			(layer "F.Fab")
			(effects
				(font
					(size 1.27 1.27)
				)
			)
		)
		(duplicate_pad_numbers_are_jumpers no)
		(fp_poly
			(pts
				(xy -0.4953 -0.2032) (xy 0.4953 -0.2032) (xy 0.4953 1.6002) (xy -0.4953 1.6002)
			)
			(stroke
				(width 0)
				(type default)
			)
			(fill no)
			(layer "F.CrtYd")
		)
		(fp_line
			(start 0.4953 -0.2032)
			(end 0.4953 1.6002)
			(stroke
				(width 0.1)
				(type default)
			)
			(layer "F.Fab")
		)
		(fp_line
			(start -0.4953 -0.2032)
			(end 0.4953 -0.2032)
			(stroke
				(width 0.1)
				(type default)
			)
			(layer "F.Fab")
		)
		(fp_line
			(start 0.4953 1.6002)
			(end -0.4953 1.6002)
			(stroke
				(width 0.1)
				(type default)
			)
			(layer "F.Fab")
		)
		(fp_line
			(start -0.4953 1.6002)
			(end -0.4953 -0.2032)
			(stroke
				(width 0.1)
				(type default)
			)
			(layer "F.Fab")
		)
		(pad "1" smd rect
			(at 0 0 90)
			(size 0.762 0.889)
			(layers "F.Cu" "F.Mask" "F.Paste")
			(net "PVPP_DEF")
		)
		(pad "2" smd rect
			(at 0 1.397 90)
			(size 0.762 0.889)
			(layers "F.Cu" "F.Mask" "F.Paste")
			(net "GND")
		)
		(zone
			(layer "F.Cu")
			(hatch none 0.5)
			(connect_pads
				(clearance 0)
			)
			(min_thickness 0.25)
			(keepout
				(tracks not_allowed)
				(vias allowed)
				(pads allowed)
				(copperpour not_allowed)
				(footprints allowed)
			)
			(placement
				(enabled no)
				(sheetname "")
			)
			(fill
				(thermal_gap 0.5)
				(thermal_bridge_width 0.5)
				(island_removal_mode 0)
			)
			(polygon
				(pts
					(xy 320.4845 -129.9718) (xy 320.4845 -130.7338) (xy 320.9925 -130.7338) (xy 320.9925 -129.9718)
				)
			)
		)
	)
	(footprint ""
		(layer "F.Cu")
		(at 363.855 -140.081 90)
		(property "Reference" "R12W30"
			(at -0.8382 -0.67818 90)
			(unlocked yes)
			(layer "F.SilkS")
			(effects
				(font
					(size 0.4064 0.254)
					(thickness 0.1524)
				)
				(justify left)
			)
		)
		(property "Value" ""
			(at 0 0 90)
			(layer "F.Fab")
			(effects
				(font
					(size 1.27 1.27)
				)
			)
		)
		(duplicate_pad_numbers_are_jumpers no)
		(fp_poly
			(pts
				(xy -0.2794 -0.1016) (xy 0.2794 -0.1016) (xy 0.2794 0.9906) (xy -0.2794 0.9906)
			)
			(stroke
				(width 0)
				(type default)
			)
			(fill no)
			(layer "F.CrtYd")
		)
		(fp_line
			(start 0.2794 -0.1016)
			(end -0.2794 -0.1016)
			(stroke
				(width 0.1)
				(type default)
			)
			(layer "F.Fab")
		)
		(fp_line
			(start -0.2794 -0.1016)
			(end -0.2794 0.9906)
			(stroke
				(width 0.1)
				(type default)
			)
			(layer "F.Fab")
		)
		(fp_line
			(start 0.2794 0.9906)
			(end 0.2794 -0.1016)
			(stroke
				(width 0.1)
				(type default)
			)
			(layer "F.Fab")
		)
		(fp_line
			(start -0.2794 0.9906)
			(end 0.2794 0.9906)
			(stroke
				(width 0.1)
				(type default)
			)
			(layer "F.Fab")
		)
		(pad "1" smd rect
			(at 0 0 90)
			(size 0.508 0.508)
			(layers "F.Cu" "F.Mask" "F.Paste")
			(net "TP_PVDDQ_DEF_MP2")
		)
		(pad "2" smd rect
			(at 0 0.889 90)
			(size 0.508 0.508)
			(layers "F.Cu" "F.Mask" "F.Paste")
			(net "PWRGD_PVDDQ_DEF")
		)
		(zone
			(layer "F.Cu")
			(hatch none 0.5)
			(connect_pads
				(clearance 0)
			)
			(min_thickness 0.25)
			(keepout
				(tracks allowed)
				(vias not_allowed)
				(pads allowed)
				(copperpour not_allowed)
				(footprints allowed)
			)
			(placement
				(enabled no)
				(sheetname "")
			)
			(fill
				(thermal_gap 0.5)
				(thermal_bridge_width 0.5)
				(island_removal_mode 0)
			)
			(polygon
				(pts
					(xy 364.109 -139.827) (xy 364.109 -140.335) (xy 364.49 -140.335) (xy 364.49 -139.827)
				)
			)
		)
		(zone
			(layer "F.Cu")
			(hatch none 0.5)
			(connect_pads
				(clearance 0)
			)
			(min_thickness 0.25)
			(keepout
				(tracks not_allowed)
				(vias allowed)
				(pads allowed)
				(copperpour not_allowed)
				(footprints allowed)
			)
			(placement
				(enabled no)
				(sheetname "")
			)
			(fill
				(thermal_gap 0.5)
				(thermal_bridge_width 0.5)
				(island_removal_mode 0)
			)
			(polygon
				(pts
					(xy 364.49 -139.827) (xy 364.49 -140.335) (xy 364.109 -140.335) (xy 364.109 -139.827)
				)
			)
		)
	)
)
